FILE_TYPE = CONNECTIVITY;
{Allegro Design Entry HDL 16.6-p007 (v16-6-112F) 10/10/2012}
"PAGE_NUMBER" = 137;
0"NC";
1"GND\g";
2"TP_IE_DEBUG_MODE";
3"FM_UART_PRES_N";
4"FM_BMC_DISABLE";
5"TP_BMC_DISABLE";
6"RST_SRTCRST_N";
7"PD_RST_RTCRST_N";
8"TP_JUMPER_BLOCK_2_8";
9"TP_JUMPER_BLOCK_2_10";
10"TP_RST_RTCRST_N";
11"RST_RTCRST_N";
12"TP_JUMPER_BLOCK_2_12";
13"FM_ROMA<0>";
14"P3V3_RTC_STBY\g";
15"P3V3_RTC_STBY\g";
16"P3V3_STBY\g";
17"GND\g";
18"GND\g";
19"PD_IE_DEBUG_MODE";
%"RES"
"1","(325,3450)","1","mstr_discrete","I11";
;
CDS_LIB"mstr_discrete"
BOM_COST"SB"
CDS_SEC"1"
$SEC"1"
CDS_LOCATION"R7C11"
ROOM"SB"
WATTAGE"1/16W"
PACK_TYPE"0402"
TOLERANCE"1%"
VALUE"1.0M"
PART_NUMBER"G21796-021"
LOCATION"R7C11"
MATERIAL"EMPTY";
"B"
$PN"2"11;
"A"
$PN"1"18;
%"CONN12_C73564003"
"1","(-2175,3675)","0","mstr_conn","I128";
;
CDS_SEC"1"
CDS_LOCATION"J9G1"
BOM_COST"SB"
CDS_LIB"mstr_conn"
SEC"1"
SEC_TYPE"PIP"
ROOM"SB"
PACK_TYPE"PIP"
MATERIAL"CONN"
PART_NUMBER"C73564-003"
LOCATION"J9G1";
"IO9"
$PN"9"3;
"IO11"
$PN"11"19;
"IO7"
$PN"7"2;
"IO3"
$PN"3"13;
"IO1"
$PN"1"5;
"IO5"
$PN"5"4;
"IO8"
$PN"8"8;
"IO10"
$PN"10"9;
"IO12"
$PN"12"12;
"IO6"
$PN"6"7;
"IO4"
$PN"4"11;
"IO2"
$PN"2"10;
%"RES"
"2","(-200,4025)","0","mstr_discrete","I13";
;
CDS_SEC"1"
CDS_LIB"mstr_discrete"
CDS_LOCATION"R7C10"
BOM_COST"SB"
SEC"1"
NO_XNET_CONNECTION"1"
SEC_TYPE"0402"
ROOM"SB"
WATTAGE"1/16W"
MATERIAL"CHIP"
PACK_TYPE"0402"
TOLERANCE"1%"
VALUE"20.0K"
PART_NUMBER"G21796-040"
LOCATION"R7C10";
"A"
$PN"1"15;
"B"
$PN"2"11;
%"CAP_A"
"1","(-125,3450)","0","dev_discrete","I14";
;
CDS_LOCATION"C7C19"
CDS_LIB"dev_discrete"
BOM_COST"SB"
CDS_SEC"1"
SEC_TYPE"0402V"
SEC"1"
ROOM"SB"
MATERIAL"X6S"
VOLTAGE"6.3V"
PACK_TYPE"0402V"
TOLERANCE"10%"
VALUE"1.0UF"
PART_NUMBER"D97712-004"
LOCATION"C7C19";
"B"
$PN"2"18;
"A"
$PN"1"11;
%"RES"
"2","(-275,3450)","2","mstr_discrete","I15";
;
CDS_SEC"1"
CDS_LOCATION"R1U63"
CDS_LIB"mstr_discrete"
SEC"1"
SEC_TYPE"0402"
BOM_COST"SB"
ROOM"SB"
WATTAGE"1/16W"
MATERIAL"CHIP"
PACK_TYPE"0402"
TOLERANCE"1%"
VALUE"1.00K"
PART_NUMBER"G21796-026"
LOCATION"R1U63";
"A"
$PN"1"7;
"B"
$PN"2"18;
%"GND"
"1","(-275,3125)","0","mstr_symbols","I16";
;
HDL_POWER"GND"
BODY_TYPE"PLUMBING"
CDS_LIB"mstr_symbols"
BOM_COST"SB"
SIZE"1B"
ROOM"WBG_HEADERS_BIOS"
VOLTAGE"0";
"A\NAC"18;
%"RES"
"2","(-275,2425)","0","mstr_discrete","I19";
;
CDS_LIB"mstr_discrete"
CDS_LOCATION"R3N4"
BOM_COST"SB"
CDS_SEC"1"
$SEC"1"
NO_XNET_CONNECTION"1"
ROOM"SB"
WATTAGE"1/16W"
MATERIAL"CHIP"
PACK_TYPE"0402"
TOLERANCE"1%"
VALUE"20.0K"
PART_NUMBER"G21796-040"
LOCATION"R3N4";
"A"
$PN"1"14;
"B"
$PN"2"6;
%"CAP_A"
"1","(-275,1975)","0","dev_discrete","I20";
;
CDS_LIB"dev_discrete"
SEC"1"
SEC_TYPE"0402V"
CDS_SEC"1"
BOM_COST"SB"
CDS_LOCATION"C3N32"
ROOM"SB"
MATERIAL"X6S"
VOLTAGE"6.3V"
PACK_TYPE"0402V"
TOLERANCE"10%"
VALUE"1.0UF"
PART_NUMBER"D97712-004"
LOCATION"C3N32";
"B"
$PN"2"17;
"A"
$PN"1"6;
%"GND"
"1","(-275,1775)","0","mstr_symbols","I21";
;
HDL_POWER"GND"
BODY_TYPE"PLUMBING"
CDS_LIB"mstr_symbols"
BOM_COST"SB"
SIZE"1B"
ROOM"WBG_HEADERS_BIOS"
VOLTAGE"0";
"A\NAC"17;
%"RES"
"2","(-2875,4225)","0","mstr_discrete","I67";
;
CDS_SEC"1"
CDS_LIB"mstr_discrete"
CDS_LOCATION"R7C13"
SEC_TYPE"0402"
BOM_COST"SB"
SEC"1"
ROOM"SB"
WATTAGE"1/16W"
MATERIAL"CHIP"
PACK_TYPE"0402"
TOLERANCE"1%"
VALUE"10.0K"
PART_NUMBER"G21796-016"
LOCATION"R7C13";
"A"
$PN"1"16;
"B"
$PN"2"3;
%"P3V3_STBY"
"1","(-2875,4450)","0","mstr_symbols","I68";
;
HDL_POWER"P3V3_STBY"
BODY_TYPE"PLUMBING"
SIZE"1B"
CDS_LIB"mstr_symbols"
VOLTAGE"3.3V";
"G\NAC"16;
%"RES"
"2","(-2875,3300)","0","mstr_discrete","I69";
;
CDS_SEC"1"
CDS_LOCATION"R1U64"
CDS_LIB"mstr_discrete"
SEC"1"
SEC_TYPE"0402"
BOM_COST"SB"
ROOM"SB"
WATTAGE"1/16W"
MATERIAL"CHIP"
PACK_TYPE"0402"
TOLERANCE"1%"
VALUE"1.00K"
PART_NUMBER"G21796-026"
LOCATION"R1U64";
"A"
$PN"1"19;
"B"
$PN"2"1;
%"GND"
"1","(-2875,3025)","0","mstr_symbols","I70";
;
HDL_POWER"GND"
BODY_TYPE"PLUMBING"
CDS_LIB"mstr_symbols"
SIZE"1B"
BOM_COST"SB"
ROOM"WBG_HEADERS_BIOS"
VOLTAGE"0";
"A\NAC"1;
%"P3V3_RTC_STBY"
"1","(-200,4225)","0","mstr_symbols","I78";
;
HDL_POWER"P3V3_RTC_STBY"
BODY_TYPE"PLUMBING"
CDS_LIB"mstr_symbols"
BOM_COST"SB"
ROOM"SB_DECOUPLING"
VOLTAGE"3.3V";
"G\NAC"15;
%"P3V3_RTC_STBY"
"1","(-275,2675)","0","mstr_symbols","I79";
;
HDL_POWER"P3V3_RTC_STBY"
BODY_TYPE"PLUMBING"
BOM_COST"SB"
CDS_LIB"mstr_symbols"
ROOM"SB_DECOUPLING"
VOLTAGE"3.3V";
"G\NAC"14;
END.
